(kicad_pcb
	(version 20260206)
	(generator "pcbnew")
	(generator_version "10.0")
	(general
		(thickness 1.6)
		(legacy_teardrops no)
	)
	(paper "A4")
	(title_block
		(title "03242023_DA0F0TMBIJ0_F0T_Motherboard_J_brd_V01_OCP.brd")
		(comment 1 "Grand Teton / footprints 4983-4989 of 6105")
	)
	(layers
		(0 "F.Cu" signal "TOP")
		(4 "In1.Cu" signal "GND")
		(6 "In2.Cu" signal "IN1")
		(8 "In3.Cu" signal "GND1")
		(10 "In4.Cu" signal "IN2")
		(12 "In5.Cu" signal "GND2")
		(14 "In6.Cu" signal "IN3")
		(16 "In7.Cu" signal "GND3")
		(18 "In8.Cu" signal "VCC")
		(20 "In9.Cu" signal "VCC1")
		(22 "In10.Cu" signal "GND4")
		(24 "In11.Cu" signal "IN4")
		(26 "In12.Cu" signal "GND5")
		(28 "In13.Cu" signal "IN5")
		(30 "In14.Cu" signal "GND6")
		(32 "In15.Cu" signal "IN6")
		(34 "In16.Cu" signal "GND7")
		(2 "B.Cu" signal "BOTTOM")
		(9 "F.Adhes" user "F.Adhesive")
		(11 "B.Adhes" user "B.Adhesive")
		(13 "F.Paste" user "Package Geometry/Pastemask Top")
		(15 "B.Paste" user "Package Geometry/Pastemask Bottom")
		(5 "F.SilkS" user "Ref Des/Silkscreen Top")
		(7 "B.SilkS" user "Ref Des/Silkscreen Bottom")
		(1 "F.Mask" user "Board Geometry/Soldermask Top")
		(3 "B.Mask" user "Board Geometry/Soldermask Bottom")
		(17 "Dwgs.User" user "User.Drawings")
		(19 "Cmts.User" user "User.Comments")
		(21 "Eco1.User" user "User.Eco1")
		(23 "Eco2.User" user "User.Eco2")
		(25 "Edge.Cuts" user "Board Geometry/Outline")
		(27 "Margin" user)
		(31 "F.CrtYd" user "Package Geometry/Place Bound Top")
		(29 "B.CrtYd" user "Package Geometry/Place Bound Bottom")
		(35 "F.Fab" user "Ref Des/Assembly Top")
		(33 "B.Fab" user "Ref Des/Assembly Bottom")
	)
	(footprint ""
		(layer "B.Cu")
		(at 328.913998 -190.74511 -90)
		(property "Reference" "R294"
			(at 0 0 90)
			(layer "B.SilkS")
			(hide yes)
			(effects
				(font
					(size 1.27 1.27)
				)
				(justify mirror)
			)
		)
		(property "Value" ""
			(at 0 0 90)
			(layer "B.Fab")
			(effects
				(font
					(size 1.27 1.27)
				)
				(justify mirror)
			)
		)
		(duplicate_pad_numbers_are_jumpers no)
		(fp_line
			(start -0.7874 0.4064)
			(end 0.7874 0.4064)
			(stroke
				(width 0.1524)
				(type default)
			)
			(layer "B.SilkS")
		)
		(fp_line
			(start 0.7874 0.4064)
			(end 0.7874 -0.4064)
			(stroke
				(width 0.1524)
				(type default)
			)
			(layer "B.SilkS")
		)
		(fp_line
			(start -0.7874 -0.4064)
			(end -0.7874 0.4064)
			(stroke
				(width 0.1524)
				(type default)
			)
			(layer "B.SilkS")
		)
		(fp_line
			(start 0.7874 -0.4064)
			(end -0.7874 -0.4064)
			(stroke
				(width 0.1524)
				(type default)
			)
			(layer "B.SilkS")
		)
		(fp_line
			(start -0.67945 0.3048)
			(end -0.120396 0.3048)
			(stroke
				(width 0.1)
				(type default)
			)
			(layer "B.Fab")
		)
		(fp_line
			(start -0.120396 0.3048)
			(end -0.120396 0.2794)
			(stroke
				(width 0.1)
				(type default)
			)
			(layer "B.Fab")
		)
		(fp_line
			(start 0.12065 0.3048)
			(end 0.67945 0.3048)
			(stroke
				(width 0.1)
				(type default)
			)
			(layer "B.Fab")
		)
		(fp_line
			(start 0.67945 0.3048)
			(end 0.67945 -0.305054)
			(stroke
				(width 0.1)
				(type default)
			)
			(layer "B.Fab")
		)
		(fp_line
			(start -0.120396 0.2794)
			(end 0.12065 0.2794)
			(stroke
				(width 0.1)
				(type default)
			)
			(layer "B.Fab")
		)
		(fp_line
			(start 0.12065 0.2794)
			(end 0.12065 0.3048)
			(stroke
				(width 0.1)
				(type default)
			)
			(layer "B.Fab")
		)
		(fp_line
			(start -0.12065 -0.2794)
			(end -0.12065 -0.3048)
			(stroke
				(width 0.1)
				(type default)
			)
			(layer "B.Fab")
		)
		(fp_line
			(start 0.12065 -0.2794)
			(end -0.12065 -0.2794)
			(stroke
				(width 0.1)
				(type default)
			)
			(layer "B.Fab")
		)
		(fp_line
			(start -0.67945 -0.3048)
			(end -0.67945 0.3048)
			(stroke
				(width 0.1)
				(type default)
			)
			(layer "B.Fab")
		)
		(fp_line
			(start -0.12065 -0.3048)
			(end -0.67945 -0.3048)
			(stroke
				(width 0.1)
				(type default)
			)
			(layer "B.Fab")
		)
		(fp_line
			(start 0.12065 -0.305054)
			(end 0.12065 -0.2794)
			(stroke
				(width 0.1)
				(type default)
			)
			(layer "B.Fab")
		)
		(fp_line
			(start 0.67945 -0.305054)
			(end 0.12065 -0.305054)
			(stroke
				(width 0.1)
				(type default)
			)
			(layer "B.Fab")
		)
		(pad "1" smd circle
			(at 0.40005 0 90)
			(size 0 0)
			(layers "B.Cu" "B.Mask" "B.Paste")
			(net "GND")
		)
		(pad "2" smd circle
			(at -0.40005 0 90)
			(size 0 0)
			(layers "B.Cu" "B.Mask" "B.Paste")
			(net "PD_CPU0_DMIMODE_OVERRIDE")
		)
	)
	(footprint ""
		(layer "B.Cu")
		(at 369.49888 -43.144948 180)
		(property "Reference" "R2509"
			(at 0 0 0)
			(layer "B.SilkS")
			(hide yes)
			(effects
				(font
					(size 1.27 1.27)
				)
				(justify mirror)
			)
		)
		(property "Value" ""
			(at 0 0 0)
			(layer "B.Fab")
			(effects
				(font
					(size 1.27 1.27)
				)
				(justify mirror)
			)
		)
		(duplicate_pad_numbers_are_jumpers no)
		(fp_line
			(start 0.7874 0.4064)
			(end 0.7874 -0.4064)
			(stroke
				(width 0.1524)
				(type default)
			)
			(layer "B.SilkS")
		)
		(fp_line
			(start 0.7874 -0.4064)
			(end -0.7874 -0.4064)
			(stroke
				(width 0.1524)
				(type default)
			)
			(layer "B.SilkS")
		)
		(fp_line
			(start -0.7874 0.4064)
			(end 0.7874 0.4064)
			(stroke
				(width 0.1524)
				(type default)
			)
			(layer "B.SilkS")
		)
		(fp_line
			(start -0.7874 -0.4064)
			(end -0.7874 0.4064)
			(stroke
				(width 0.1524)
				(type default)
			)
			(layer "B.SilkS")
		)
		(fp_line
			(start 0.67945 0.3048)
			(end 0.67945 -0.305054)
			(stroke
				(width 0.1)
				(type default)
			)
			(layer "B.Fab")
		)
		(fp_line
			(start 0.67945 -0.305054)
			(end 0.12065 -0.305054)
			(stroke
				(width 0.1)
				(type default)
			)
			(layer "B.Fab")
		)
		(fp_line
			(start 0.12065 0.3048)
			(end 0.67945 0.3048)
			(stroke
				(width 0.1)
				(type default)
			)
			(layer "B.Fab")
		)
		(fp_line
			(start 0.12065 0.2794)
			(end 0.12065 0.3048)
			(stroke
				(width 0.1)
				(type default)
			)
			(layer "B.Fab")
		)
		(fp_line
			(start 0.12065 -0.2794)
			(end -0.12065 -0.2794)
			(stroke
				(width 0.1)
				(type default)
			)
			(layer "B.Fab")
		)
		(fp_line
			(start 0.12065 -0.305054)
			(end 0.12065 -0.2794)
			(stroke
				(width 0.1)
				(type default)
			)
			(layer "B.Fab")
		)
		(fp_line
			(start -0.120396 0.3048)
			(end -0.120396 0.2794)
			(stroke
				(width 0.1)
				(type default)
			)
			(layer "B.Fab")
		)
		(fp_line
			(start -0.120396 0.2794)
			(end 0.12065 0.2794)
			(stroke
				(width 0.1)
				(type default)
			)
			(layer "B.Fab")
		)
		(fp_line
			(start -0.12065 -0.2794)
			(end -0.12065 -0.3048)
			(stroke
				(width 0.1)
				(type default)
			)
			(layer "B.Fab")
		)
		(fp_line
			(start -0.12065 -0.3048)
			(end -0.67945 -0.3048)
			(stroke
				(width 0.1)
				(type default)
			)
			(layer "B.Fab")
		)
		(fp_line
			(start -0.67945 0.3048)
			(end -0.120396 0.3048)
			(stroke
				(width 0.1)
				(type default)
			)
			(layer "B.Fab")
		)
		(fp_line
			(start -0.67945 -0.3048)
			(end -0.67945 0.3048)
			(stroke
				(width 0.1)
				(type default)
			)
			(layer "B.Fab")
		)
		(pad "1" smd circle
			(at 0.40005 0)
			(size 0 0)
			(layers "B.Cu" "B.Mask" "B.Paste")
			(net "FM_M2_SSD0_E7_PEDET")
		)
		(pad "2" smd circle
			(at -0.40005 0)
			(size 0 0)
			(layers "B.Cu" "B.Mask" "B.Paste")
			(net "GND")
		)
	)
	(footprint ""
		(layer "B.Cu")
		(at 292.528498 -400.999452 -90)
		(property "Reference" "PR2527"
			(at 0 0 90)
			(layer "B.SilkS")
			(hide yes)
			(effects
				(font
					(size 1.27 1.27)
				)
				(justify mirror)
			)
		)
		(property "Value" ""
			(at 0 0 90)
			(layer "B.Fab")
			(effects
				(font
					(size 1.27 1.27)
				)
				(justify mirror)
			)
		)
		(duplicate_pad_numbers_are_jumpers no)
		(fp_line
			(start -0.7874 0.4064)
			(end 0.7874 0.4064)
			(stroke
				(width 0.1524)
				(type default)
			)
			(layer "B.SilkS")
		)
		(fp_line
			(start 0.7874 0.4064)
			(end 0.7874 -0.4064)
			(stroke
				(width 0.1524)
				(type default)
			)
			(layer "B.SilkS")
		)
		(fp_line
			(start -0.7874 -0.4064)
			(end -0.7874 0.4064)
			(stroke
				(width 0.1524)
				(type default)
			)
			(layer "B.SilkS")
		)
		(fp_line
			(start 0.7874 -0.4064)
			(end -0.7874 -0.4064)
			(stroke
				(width 0.1524)
				(type default)
			)
			(layer "B.SilkS")
		)
		(fp_line
			(start -0.67945 0.3048)
			(end -0.120396 0.3048)
			(stroke
				(width 0.1)
				(type default)
			)
			(layer "B.Fab")
		)
		(fp_line
			(start -0.120396 0.3048)
			(end -0.120396 0.2794)
			(stroke
				(width 0.1)
				(type default)
			)
			(layer "B.Fab")
		)
		(fp_line
			(start 0.12065 0.3048)
			(end 0.67945 0.3048)
			(stroke
				(width 0.1)
				(type default)
			)
			(layer "B.Fab")
		)
		(fp_line
			(start 0.67945 0.3048)
			(end 0.67945 -0.305054)
			(stroke
				(width 0.1)
				(type default)
			)
			(layer "B.Fab")
		)
		(fp_line
			(start -0.120396 0.2794)
			(end 0.12065 0.2794)
			(stroke
				(width 0.1)
				(type default)
			)
			(layer "B.Fab")
		)
		(fp_line
			(start 0.12065 0.2794)
			(end 0.12065 0.3048)
			(stroke
				(width 0.1)
				(type default)
			)
			(layer "B.Fab")
		)
		(fp_line
			(start -0.12065 -0.2794)
			(end -0.12065 -0.3048)
			(stroke
				(width 0.1)
				(type default)
			)
			(layer "B.Fab")
		)
		(fp_line
			(start 0.12065 -0.2794)
			(end -0.12065 -0.2794)
			(stroke
				(width 0.1)
				(type default)
			)
			(layer "B.Fab")
		)
		(fp_line
			(start -0.67945 -0.3048)
			(end -0.67945 0.3048)
			(stroke
				(width 0.1)
				(type default)
			)
			(layer "B.Fab")
		)
		(fp_line
			(start -0.12065 -0.3048)
			(end -0.67945 -0.3048)
			(stroke
				(width 0.1)
				(type default)
			)
			(layer "B.Fab")
		)
		(fp_line
			(start 0.12065 -0.305054)
			(end 0.12065 -0.2794)
			(stroke
				(width 0.1)
				(type default)
			)
			(layer "B.Fab")
		)
		(fp_line
			(start 0.67945 -0.305054)
			(end 0.12065 -0.305054)
			(stroke
				(width 0.1)
				(type default)
			)
			(layer "B.Fab")
		)
		(pad "1" smd circle
			(at 0.40005 0 90)
			(size 0 0)
			(layers "B.Cu" "B.Mask" "B.Paste")
			(net "P12V_HSC_SENSE2_N")
		)
		(pad "2" smd circle
			(at -0.40005 0 90)
			(size 0 0)
			(layers "B.Cu" "B.Mask" "B.Paste")
			(net "P12V_HSC_SENSE2_R4_N")
		)
	)
	(footprint ""
		(layer "B.Cu")
		(at 355.397308 -255.853946 -90)
		(property "Reference" "C362"
			(at 0 0 90)
			(layer "B.SilkS")
			(hide yes)
			(effects
				(font
					(size 1.27 1.27)
				)
				(justify mirror)
			)
		)
		(property "Value" ""
			(at 0 0 90)
			(layer "B.Fab")
			(effects
				(font
					(size 1.27 1.27)
				)
				(justify mirror)
			)
		)
		(duplicate_pad_numbers_are_jumpers no)
		(fp_line
			(start -1.524 0.762)
			(end 1.524 0.762)
			(stroke
				(width 0.1524)
				(type default)
			)
			(layer "B.SilkS")
		)
		(fp_line
			(start 1.524 0.762)
			(end 1.524 -0.762)
			(stroke
				(width 0.1524)
				(type default)
			)
			(layer "B.SilkS")
		)
		(fp_line
			(start -1.524 -0.762)
			(end -1.524 0.762)
			(stroke
				(width 0.1524)
				(type default)
			)
			(layer "B.SilkS")
		)
		(fp_line
			(start 1.524 -0.762)
			(end -1.524 -0.762)
			(stroke
				(width 0.1524)
				(type default)
			)
			(layer "B.SilkS")
		)
		(fp_line
			(start -1.1049 0.724916)
			(end -1.1049 -0.724916)
			(stroke
				(width 0.1)
				(type default)
			)
			(layer "B.Fab")
		)
		(fp_line
			(start 1.1049 0.724916)
			(end -1.1049 0.724916)
			(stroke
				(width 0.1)
				(type default)
			)
			(layer "B.Fab")
		)
		(fp_line
			(start -1.1049 -0.724916)
			(end 1.1049 -0.724916)
			(stroke
				(width 0.1)
				(type default)
			)
			(layer "B.Fab")
		)
		(fp_line
			(start 1.1049 -0.724916)
			(end 1.1049 0.724916)
			(stroke
				(width 0.1)
				(type default)
			)
			(layer "B.Fab")
		)
		(pad "1" smd rect
			(at 0.889 0 270)
			(size 1.016 1.27)
			(layers "B.Cu" "B.Mask" "B.Paste")
			(net "PVCCIN_CPU0")
		)
		(pad "2" smd rect
			(at -0.889 0 270)
			(size 1.016 1.27)
			(layers "B.Cu" "B.Mask" "B.Paste")
			(net "GND")
		)
	)
	(footprint ""
		(layer "B.Cu")
		(at 114.374676 -360.418126 -90)
		(property "Reference" "PR304"
			(at 0 0 90)
			(layer "B.SilkS")
			(hide yes)
			(effects
				(font
					(size 1.27 1.27)
				)
				(justify mirror)
			)
		)
		(property "Value" ""
			(at 0 0 90)
			(layer "B.Fab")
			(effects
				(font
					(size 1.27 1.27)
				)
				(justify mirror)
			)
		)
		(duplicate_pad_numbers_are_jumpers no)
		(fp_line
			(start -0.7874 0.4064)
			(end 0.7874 0.4064)
			(stroke
				(width 0.1524)
				(type default)
			)
			(layer "B.SilkS")
		)
		(fp_line
			(start 0.7874 0.4064)
			(end 0.7874 -0.4064)
			(stroke
				(width 0.1524)
				(type default)
			)
			(layer "B.SilkS")
		)
		(fp_line
			(start -0.7874 -0.4064)
			(end -0.7874 0.4064)
			(stroke
				(width 0.1524)
				(type default)
			)
			(layer "B.SilkS")
		)
		(fp_line
			(start 0.7874 -0.4064)
			(end -0.7874 -0.4064)
			(stroke
				(width 0.1524)
				(type default)
			)
			(layer "B.SilkS")
		)
		(fp_line
			(start -0.67945 0.3048)
			(end -0.120396 0.3048)
			(stroke
				(width 0.1)
				(type default)
			)
			(layer "B.Fab")
		)
		(fp_line
			(start -0.120396 0.3048)
			(end -0.120396 0.2794)
			(stroke
				(width 0.1)
				(type default)
			)
			(layer "B.Fab")
		)
		(fp_line
			(start 0.12065 0.3048)
			(end 0.67945 0.3048)
			(stroke
				(width 0.1)
				(type default)
			)
			(layer "B.Fab")
		)
		(fp_line
			(start 0.67945 0.3048)
			(end 0.67945 -0.305054)
			(stroke
				(width 0.1)
				(type default)
			)
			(layer "B.Fab")
		)
		(fp_line
			(start -0.120396 0.2794)
			(end 0.12065 0.2794)
			(stroke
				(width 0.1)
				(type default)
			)
			(layer "B.Fab")
		)
		(fp_line
			(start 0.12065 0.2794)
			(end 0.12065 0.3048)
			(stroke
				(width 0.1)
				(type default)
			)
			(layer "B.Fab")
		)
		(fp_line
			(start -0.12065 -0.2794)
			(end -0.12065 -0.3048)
			(stroke
				(width 0.1)
				(type default)
			)
			(layer "B.Fab")
		)
		(fp_line
			(start 0.12065 -0.2794)
			(end -0.12065 -0.2794)
			(stroke
				(width 0.1)
				(type default)
			)
			(layer "B.Fab")
		)
		(fp_line
			(start -0.67945 -0.3048)
			(end -0.67945 0.3048)
			(stroke
				(width 0.1)
				(type default)
			)
			(layer "B.Fab")
		)
		(fp_line
			(start -0.12065 -0.3048)
			(end -0.67945 -0.3048)
			(stroke
				(width 0.1)
				(type default)
			)
			(layer "B.Fab")
		)
		(fp_line
			(start 0.12065 -0.305054)
			(end 0.12065 -0.2794)
			(stroke
				(width 0.1)
				(type default)
			)
			(layer "B.Fab")
		)
		(fp_line
			(start 0.67945 -0.305054)
			(end 0.12065 -0.305054)
			(stroke
				(width 0.1)
				(type default)
			)
			(layer "B.Fab")
		)
		(pad "1" smd circle
			(at 0.40005 0 90)
			(size 0 0)
			(layers "B.Cu" "B.Mask" "B.Paste")
			(net "P12V_AUX")
		)
		(pad "2" smd circle
			(at -0.40005 0 90)
			(size 0 0)
			(layers "B.Cu" "B.Mask" "B.Paste")
			(net "PVCCIN_CPU1_CSPIN")
		)
	)
	(footprint ""
		(layer "B.Cu")
		(at 146.3548 -13.772388 90)
		(property "Reference" "R4087"
			(at 0 0 90)
			(layer "B.SilkS")
			(hide yes)
			(effects
				(font
					(size 1.27 1.27)
				)
				(justify mirror)
			)
		)
		(property "Value" ""
			(at 0 0 90)
			(layer "B.Fab")
			(effects
				(font
					(size 1.27 1.27)
				)
				(justify mirror)
			)
		)
		(duplicate_pad_numbers_are_jumpers no)
		(fp_line
			(start 0.7874 -0.4064)
			(end -0.7874 -0.4064)
			(stroke
				(width 0.1524)
				(type default)
			)
			(layer "B.SilkS")
		)
		(fp_line
			(start -0.7874 -0.4064)
			(end -0.7874 0.4064)
			(stroke
				(width 0.1524)
				(type default)
			)
			(layer "B.SilkS")
		)
		(fp_line
			(start 0.7874 0.4064)
			(end 0.7874 -0.4064)
			(stroke
				(width 0.1524)
				(type default)
			)
			(layer "B.SilkS")
		)
		(fp_line
			(start -0.7874 0.4064)
			(end 0.7874 0.4064)
			(stroke
				(width 0.1524)
				(type default)
			)
			(layer "B.SilkS")
		)
		(fp_line
			(start 0.67945 -0.305054)
			(end 0.12065 -0.305054)
			(stroke
				(width 0.1)
				(type default)
			)
			(layer "B.Fab")
		)
		(fp_line
			(start 0.12065 -0.305054)
			(end 0.12065 -0.2794)
			(stroke
				(width 0.1)
				(type default)
			)
			(layer "B.Fab")
		)
		(fp_line
			(start -0.12065 -0.3048)
			(end -0.67945 -0.3048)
			(stroke
				(width 0.1)
				(type default)
			)
			(layer "B.Fab")
		)
		(fp_line
			(start -0.67945 -0.3048)
			(end -0.67945 0.3048)
			(stroke
				(width 0.1)
				(type default)
			)
			(layer "B.Fab")
		)
		(fp_line
			(start 0.12065 -0.2794)
			(end -0.12065 -0.2794)
			(stroke
				(width 0.1)
				(type default)
			)
			(layer "B.Fab")
		)
		(fp_line
			(start -0.12065 -0.2794)
			(end -0.12065 -0.3048)
			(stroke
				(width 0.1)
				(type default)
			)
			(layer "B.Fab")
		)
		(fp_line
			(start 0.12065 0.2794)
			(end 0.12065 0.3048)
			(stroke
				(width 0.1)
				(type default)
			)
			(layer "B.Fab")
		)
		(fp_line
			(start -0.120396 0.2794)
			(end 0.12065 0.2794)
			(stroke
				(width 0.1)
				(type default)
			)
			(layer "B.Fab")
		)
		(fp_line
			(start 0.67945 0.3048)
			(end 0.67945 -0.305054)
			(stroke
				(width 0.1)
				(type default)
			)
			(layer "B.Fab")
		)
		(fp_line
			(start 0.12065 0.3048)
			(end 0.67945 0.3048)
			(stroke
				(width 0.1)
				(type default)
			)
			(layer "B.Fab")
		)
		(fp_line
			(start -0.120396 0.3048)
			(end -0.120396 0.2794)
			(stroke
				(width 0.1)
				(type default)
			)
			(layer "B.Fab")
		)
		(fp_line
			(start -0.67945 0.3048)
			(end -0.120396 0.3048)
			(stroke
				(width 0.1)
				(type default)
			)
			(layer "B.Fab")
		)
		(pad "1" smd circle
			(at 0.40005 0 270)
			(size 0 0)
			(layers "B.Cu" "B.Mask" "B.Paste")
			(net "FM_JTAG_BMC_MUX_SEL_FROM_BMC_R")
		)
		(pad "2" smd circle
			(at -0.40005 0 270)
			(size 0 0)
			(layers "B.Cu" "B.Mask" "B.Paste")
			(net "FM_JTAG_BMC_MUX_SEL_FROM_BMC_R2")
		)
	)
	(footprint ""
		(layer "B.Cu")
		(at 366.120934 -259.531866 90)
		(property "Reference" "C493"
			(at 0 0 90)
			(layer "B.SilkS")
			(hide yes)
			(effects
				(font
					(size 1.27 1.27)
				)
				(justify mirror)
			)
		)
		(property "Value" ""
			(at 0 0 90)
			(layer "B.Fab")
			(effects
				(font
					(size 1.27 1.27)
				)
				(justify mirror)
			)
		)
		(duplicate_pad_numbers_are_jumpers no)
		(fp_line
			(start 1.524 -0.762)
			(end -1.524 -0.762)
			(stroke
				(width 0.1524)
				(type default)
			)
			(layer "B.SilkS")
		)
		(fp_line
			(start -1.524 -0.762)
			(end -1.524 0.762)
			(stroke
				(width 0.1524)
				(type default)
			)
			(layer "B.SilkS")
		)
		(fp_line
			(start 1.524 0.762)
			(end 1.524 -0.762)
			(stroke
				(width 0.1524)
				(type default)
			)
			(layer "B.SilkS")
		)
		(fp_line
			(start -1.524 0.762)
			(end 1.524 0.762)
			(stroke
				(width 0.1524)
				(type default)
			)
			(layer "B.SilkS")
		)
		(fp_line
			(start 1.1049 -0.724916)
			(end 1.1049 0.724916)
			(stroke
				(width 0.1)
				(type default)
			)
			(layer "B.Fab")
		)
		(fp_line
			(start -1.1049 -0.724916)
			(end 1.1049 -0.724916)
			(stroke
				(width 0.1)
				(type default)
			)
			(layer "B.Fab")
		)
		(fp_line
			(start 1.1049 0.724916)
			(end -1.1049 0.724916)
			(stroke
				(width 0.1)
				(type default)
			)
			(layer "B.Fab")
		)
		(fp_line
			(start -1.1049 0.724916)
			(end -1.1049 -0.724916)
			(stroke
				(width 0.1)
				(type default)
			)
			(layer "B.Fab")
		)
		(pad "1" smd rect
			(at 0.889 0 90)
			(size 1.016 1.27)
			(layers "B.Cu" "B.Mask" "B.Paste")
			(net "PVCCFA_EHV_FIVRA_CPU0")
		)
		(pad "2" smd rect
			(at -0.889 0 90)
			(size 1.016 1.27)
			(layers "B.Cu" "B.Mask" "B.Paste")
			(net "GND")
		)
	)
)
